# S9S_MB_2U (Grand Teton) — schematic netlist excerpt (pin names and nets, part order shuffled) for the footprints in the layout excerpt that follows; sources: Cadence DE-HDL packaged netlist, KiCad conversion of 03242023_DA0F0TMBIJ0_F0T_Motherboard_J_brd_V01_OCP.brd

R4074  Q_RES  10K 1% EMPTY  pkg 0402LF  page 192 : A = P12V_AUX ; B = P12V_E1S_0_EN_G

(kicad_pcb
	(version 20260206)
	(generator "pcbnew")
	(generator_version "10.0")
	(general
		(thickness 1.6)
		(legacy_teardrops no)
	)
	(paper "A4")
	(title_block
		(title "03242023_DA0F0TMBIJ0_F0T_Motherboard_J_brd_V01_OCP.brd")
		(comment 1 "Grand Teton / footprints 3834-3834 of 6105")
	)
	(layers
		(0 "F.Cu" signal "TOP")
		(4 "In1.Cu" signal "GND")
		(6 "In2.Cu" signal "IN1")
		(8 "In3.Cu" signal "GND1")
		(10 "In4.Cu" signal "IN2")
		(12 "In5.Cu" signal "GND2")
		(14 "In6.Cu" signal "IN3")
		(16 "In7.Cu" signal "GND3")
		(18 "In8.Cu" signal "VCC")
		(20 "In9.Cu" signal "VCC1")
		(22 "In10.Cu" signal "GND4")
		(24 "In11.Cu" signal "IN4")
		(26 "In12.Cu" signal "GND5")
		(28 "In13.Cu" signal "IN5")
		(30 "In14.Cu" signal "GND6")
		(32 "In15.Cu" signal "IN6")
		(34 "In16.Cu" signal "GND7")
		(2 "B.Cu" signal "BOTTOM")
		(9 "F.Adhes" user "F.Adhesive")
		(11 "B.Adhes" user "B.Adhesive")
		(13 "F.Paste" user "Package Geometry/Pastemask Top")
		(15 "B.Paste" user "Package Geometry/Pastemask Bottom")
		(5 "F.SilkS" user "Ref Des/Silkscreen Top")
		(7 "B.SilkS" user "Ref Des/Silkscreen Bottom")
		(1 "F.Mask" user "Board Geometry/Soldermask Top")
		(3 "B.Mask" user "Board Geometry/Soldermask Bottom")
		(17 "Dwgs.User" user "User.Drawings")
		(19 "Cmts.User" user "User.Comments")
		(21 "Eco1.User" user "User.Eco1")
		(23 "Eco2.User" user "User.Eco2")
		(25 "Edge.Cuts" user "Board Geometry/Outline")
		(27 "Margin" user)
		(31 "F.CrtYd" user "Package Geometry/Place Bound Top")
		(29 "B.CrtYd" user "Package Geometry/Place Bound Bottom")
		(35 "F.Fab" user "Ref Des/Assembly Top")
		(33 "B.Fab" user "Ref Des/Assembly Bottom")
	)
	(footprint ""
		(layer "F.Cu")
		(at 292.19398 -53.652674)
		(property "Reference" "R4074"
			(at 0 0 0)
			(layer "F.SilkS")
			(hide yes)
			(effects
				(font
					(size 1.27 1.27)
				)
			)
		)
		(property "Value" ""
			(at 0 0 0)
			(layer "F.Fab")
			(effects
				(font
					(size 1.27 1.27)
				)
			)
		)
		(duplicate_pad_numbers_are_jumpers no)
		(fp_line
			(start -0.7874 -0.4064)
			(end 0.7874 -0.4064)
			(stroke
				(width 0.1524)
				(type default)
			)
			(layer "F.SilkS")
		)
		(fp_line
			(start -0.7874 0.4064)
			(end -0.7874 -0.4064)
			(stroke
				(width 0.1524)
				(type default)
			)
			(layer "F.SilkS")
		)
		(fp_line
			(start 0.7874 -0.4064)
			(end 0.7874 0.4064)
			(stroke
				(width 0.1524)
				(type default)
			)
			(layer "F.SilkS")
		)
		(fp_line
			(start 0.7874 0.4064)
			(end -0.7874 0.4064)
			(stroke
				(width 0.1524)
				(type default)
			)
			(layer "F.SilkS")
		)
		(fp_line
			(start -0.67945 -0.305054)
			(end -0.12065 -0.305054)
			(stroke
				(width 0.1)
				(type default)
			)
			(layer "F.Fab")
		)
		(fp_line
			(start -0.67945 0.3048)
			(end -0.67945 -0.305054)
			(stroke
				(width 0.1)
				(type default)
			)
			(layer "F.Fab")
		)
		(fp_line
			(start -0.12065 -0.305054)
			(end -0.12065 -0.2794)
			(stroke
				(width 0.1)
				(type default)
			)
			(layer "F.Fab")
		)
		(fp_line
			(start -0.12065 -0.2794)
			(end 0.12065 -0.2794)
			(stroke
				(width 0.1)
				(type default)
			)
			(layer "F.Fab")
		)
		(fp_line
			(start -0.12065 0.2794)
			(end -0.12065 0.3048)
			(stroke
				(width 0.1)
				(type default)
			)
			(layer "F.Fab")
		)
		(fp_line
			(start -0.12065 0.3048)
			(end -0.67945 0.3048)
			(stroke
				(width 0.1)
				(type default)
			)
			(layer "F.Fab")
		)
		(fp_line
			(start 0.120396 0.2794)
			(end -0.12065 0.2794)
			(stroke
				(width 0.1)
				(type default)
			)
			(layer "F.Fab")
		)
		(fp_line
			(start 0.120396 0.3048)
			(end 0.120396 0.2794)
			(stroke
				(width 0.1)
				(type default)
			)
			(layer "F.Fab")
		)
		(fp_line
			(start 0.12065 -0.3048)
			(end 0.67945 -0.3048)
			(stroke
				(width 0.1)
				(type default)
			)
			(layer "F.Fab")
		)
		(fp_line
			(start 0.12065 -0.2794)
			(end 0.12065 -0.3048)
			(stroke
				(width 0.1)
				(type default)
			)
			(layer "F.Fab")
		)
		(fp_line
			(start 0.67945 -0.3048)
			(end 0.67945 0.3048)
			(stroke
				(width 0.1)
				(type default)
			)
			(layer "F.Fab")
		)
		(fp_line
			(start 0.67945 0.3048)
			(end 0.120396 0.3048)
			(stroke
				(width 0.1)
				(type default)
			)
			(layer "F.Fab")
		)
		(pad "1" smd circle
			(at -0.40005 0)
			(size 0 0)
			(layers "F.Cu" "F.Mask" "F.Paste")
			(net "P12V_AUX")
		)
		(pad "2" smd circle
			(at 0.40005 0)
			(size 0 0)
			(layers "F.Cu" "F.Mask" "F.Paste")
			(net "P12V_E1S_0_EN_G")
		)
	)
)
